FILE_TYPE = MACRO_DRAWING;
SET COLOR_WIRE YELLOW;
SET COLOR_PROP ORANGE;
SET COLOR_DOT WHITE;
SET COLOR_ARC YELLOW;
SET COLOR_BODY GREEN;
SET COLOR_NOTE PURPLE;
SET PROP_DISPLAY VALUE;
SET PAGE_NUMBER P1;
FORCEADD SYNONYM..1
(1850 2050);
PAINT MONO (1850 2050);
FORCEPROP 2 LAST PATH 4P
J 0
(1850 2150);
DISPLAY 0.872340 (1850 2150);
PAINT YELLOW (1850 2150);
FORCEPROP 1 LAST NEEDS_NO_SIZE TRUE
J 0
(1875 2125);
DISPLAY 0.872340 (1875 2125);
PAINT MONO (1875 2125);
DISPLAY INVISIBLE (1875 2125);
FORCEPROP 1 LAST BODY_TYPE PLUMBING
J 0
(1850 2100);
DISPLAY 0.872340 (1850 2100);
PAINT GREEN (1850 2100);
DISPLAY INVISIBLE (1850 2100);
FORCEPROP 2 LAST CDS_LIB mstr_standard
J 0
(1850 2050);
DISPLAY 0.851064 (1850 2050);
DISPLAY INVISIBLE (1850 2050);
FORCEADD DRAWING..2
(1275 1750);
PAINT MONO (1275 1750);
FORCEPROP 1 LAST LAST_MODIFIED Tue Oct 25 14:25:02 2011
J 0
(1575 1500);
DISPLAY 0.872340 (1575 1500);
PAINT GREEN (1575 1500);
FORCEPROP 1 LAST TITLE P3V3
J 0
(1325 1700);
DISPLAY 0.872340 (1325 1700);
PAINT GREEN (1325 1700);
FORCEPROP 1 LAST ABBREV P3V3
J 0
(1325 1650);
DISPLAY 0.872340 (1325 1650);
PAINT GREEN (1325 1650);
WIRE 16 -1 (1800 2050)(1200 2050);
FORCEPROP 2 LAST SIG_NAME G\I
J 0
(1025 2060);
DISPLAY 0.872340 (1025 2060);
PAINT MONO (1025 2060);
WIRE 0 -1 (1900 2050)(2050 2050);
FORCEPROP 2 LAST SIG_NAME P3V3 \G
J 0
(2075 2085);
DISPLAY 0.872340 (2075 2085);
PAINT MONO (2075 2085);
QUIT
